# S9S_MB_2U (Grand Teton) — schematic netlist excerpt (pin names and nets, part order shuffled) for the footprints in the layout excerpt that follows; sources: Cadence DE-HDL packaged netlist, KiCad conversion of 03242023_DA0F0TMBIJ0_F0T_Motherboard_J_brd_V01_OCP.brd

R1371  Q_RES  130 1% CHIP  pkg 0402LF  page 256 : A = LED_RST_PLD_CPU0_DRAM_AB_N ; B = P3V3_AUX
C276  Q_CAP  22UF 4V 20% X6S  pkg C0402  page 77 : A = PVCCIN_CPU1 ; B = GND

(kicad_pcb
	(version 20260206)
	(generator "pcbnew")
	(generator_version "10.0")
	(general
		(thickness 1.6)
		(legacy_teardrops no)
	)
	(paper "A4")
	(title_block
		(title "03242023_DA0F0TMBIJ0_F0T_Motherboard_J_brd_V01_OCP.brd")
		(comment 1 "Grand Teton / footprints 2457-2458 of 6105")
	)
	(layers
		(0 "F.Cu" signal "TOP")
		(4 "In1.Cu" signal "GND")
		(6 "In2.Cu" signal "IN1")
		(8 "In3.Cu" signal "GND1")
		(10 "In4.Cu" signal "IN2")
		(12 "In5.Cu" signal "GND2")
		(14 "In6.Cu" signal "IN3")
		(16 "In7.Cu" signal "GND3")
		(18 "In8.Cu" signal "VCC")
		(20 "In9.Cu" signal "VCC1")
		(22 "In10.Cu" signal "GND4")
		(24 "In11.Cu" signal "IN4")
		(26 "In12.Cu" signal "GND5")
		(28 "In13.Cu" signal "IN5")
		(30 "In14.Cu" signal "GND6")
		(32 "In15.Cu" signal "IN6")
		(34 "In16.Cu" signal "GND7")
		(2 "B.Cu" signal "BOTTOM")
		(9 "F.Adhes" user "F.Adhesive")
		(11 "B.Adhes" user "B.Adhesive")
		(13 "F.Paste" user "Package Geometry/Pastemask Top")
		(15 "B.Paste" user "Package Geometry/Pastemask Bottom")
		(5 "F.SilkS" user "Ref Des/Silkscreen Top")
		(7 "B.SilkS" user "Ref Des/Silkscreen Bottom")
		(1 "F.Mask" user "Board Geometry/Soldermask Top")
		(3 "B.Mask" user "Board Geometry/Soldermask Bottom")
		(17 "Dwgs.User" user "User.Drawings")
		(19 "Cmts.User" user "User.Comments")
		(21 "Eco1.User" user "User.Eco1")
		(23 "Eco2.User" user "User.Eco2")
		(25 "Edge.Cuts" user "Board Geometry/Outline")
		(27 "Margin" user)
		(31 "F.CrtYd" user "Package Geometry/Place Bound Top")
		(29 "B.CrtYd" user "Package Geometry/Place Bound Bottom")
		(35 "F.Fab" user "Ref Des/Assembly Top")
		(33 "B.Fab" user "Ref Des/Assembly Bottom")
	)
	(footprint ""
		(layer "F.Cu")
		(at 80.550766 -65.082674 -90)
		(property "Reference" "R1371"
			(at 0 0 270)
			(layer "F.SilkS")
			(hide yes)
			(effects
				(font
					(size 1.27 1.27)
				)
			)
		)
		(property "Value" ""
			(at 0 0 270)
			(layer "F.Fab")
			(effects
				(font
					(size 1.27 1.27)
				)
			)
		)
		(duplicate_pad_numbers_are_jumpers no)
		(fp_line
			(start -0.7874 0.4064)
			(end -0.7874 -0.4064)
			(stroke
				(width 0.1524)
				(type default)
			)
			(layer "F.SilkS")
		)
		(fp_line
			(start 0.7874 0.4064)
			(end -0.7874 0.4064)
			(stroke
				(width 0.1524)
				(type default)
			)
			(layer "F.SilkS")
		)
		(fp_line
			(start -0.7874 -0.4064)
			(end 0.7874 -0.4064)
			(stroke
				(width 0.1524)
				(type default)
			)
			(layer "F.SilkS")
		)
		(fp_line
			(start 0.7874 -0.4064)
			(end 0.7874 0.4064)
			(stroke
				(width 0.1524)
				(type default)
			)
			(layer "F.SilkS")
		)
		(fp_line
			(start -0.67945 0.3048)
			(end -0.67945 -0.305054)
			(stroke
				(width 0.1)
				(type default)
			)
			(layer "F.Fab")
		)
		(fp_line
			(start -0.12065 0.3048)
			(end -0.67945 0.3048)
			(stroke
				(width 0.1)
				(type default)
			)
			(layer "F.Fab")
		)
		(fp_line
			(start 0.120396 0.3048)
			(end 0.120396 0.2794)
			(stroke
				(width 0.1)
				(type default)
			)
			(layer "F.Fab")
		)
		(fp_line
			(start 0.67945 0.3048)
			(end 0.120396 0.3048)
			(stroke
				(width 0.1)
				(type default)
			)
			(layer "F.Fab")
		)
		(fp_line
			(start -0.12065 0.2794)
			(end -0.12065 0.3048)
			(stroke
				(width 0.1)
				(type default)
			)
			(layer "F.Fab")
		)
		(fp_line
			(start 0.120396 0.2794)
			(end -0.12065 0.2794)
			(stroke
				(width 0.1)
				(type default)
			)
			(layer "F.Fab")
		)
		(fp_line
			(start -0.12065 -0.2794)
			(end 0.12065 -0.2794)
			(stroke
				(width 0.1)
				(type default)
			)
			(layer "F.Fab")
		)
		(fp_line
			(start 0.12065 -0.2794)
			(end 0.12065 -0.3048)
			(stroke
				(width 0.1)
				(type default)
			)
			(layer "F.Fab")
		)
		(fp_line
			(start 0.12065 -0.3048)
			(end 0.67945 -0.3048)
			(stroke
				(width 0.1)
				(type default)
			)
			(layer "F.Fab")
		)
		(fp_line
			(start 0.67945 -0.3048)
			(end 0.67945 0.3048)
			(stroke
				(width 0.1)
				(type default)
			)
			(layer "F.Fab")
		)
		(fp_line
			(start -0.67945 -0.305054)
			(end -0.12065 -0.305054)
			(stroke
				(width 0.1)
				(type default)
			)
			(layer "F.Fab")
		)
		(fp_line
			(start -0.12065 -0.305054)
			(end -0.12065 -0.2794)
			(stroke
				(width 0.1)
				(type default)
			)
			(layer "F.Fab")
		)
		(pad "1" smd circle
			(at -0.40005 0 270)
			(size 0 0)
			(layers "F.Cu" "F.Mask" "F.Paste")
			(net "LED_RST_PLD_CPU0_DRAM_AB_N")
		)
		(pad "2" smd circle
			(at 0.40005 0 270)
			(size 0 0)
			(layers "F.Cu" "F.Mask" "F.Paste")
			(net "P3V3_AUX")
		)
	)
	(footprint ""
		(layer "F.Cu")
		(at 106.331004 -245.634256 -90)
		(property "Reference" "C276"
			(at 0 0 270)
			(layer "F.SilkS")
			(hide yes)
			(effects
				(font
					(size 1.27 1.27)
				)
			)
		)
		(property "Value" ""
			(at 0 0 270)
			(layer "F.Fab")
			(effects
				(font
					(size 1.27 1.27)
				)
			)
		)
		(duplicate_pad_numbers_are_jumpers no)
		(fp_line
			(start -0.7874 0.4064)
			(end -0.7874 -0.4064)
			(stroke
				(width 0.1524)
				(type default)
			)
			(layer "F.SilkS")
		)
		(fp_line
			(start 0.7874 0.4064)
			(end -0.7874 0.4064)
			(stroke
				(width 0.1524)
				(type default)
			)
			(layer "F.SilkS")
		)
		(fp_line
			(start -0.7874 -0.4064)
			(end 0.7874 -0.4064)
			(stroke
				(width 0.1524)
				(type default)
			)
			(layer "F.SilkS")
		)
		(fp_line
			(start 0.7874 -0.4064)
			(end 0.7874 0.4064)
			(stroke
				(width 0.1524)
				(type default)
			)
			(layer "F.SilkS")
		)
		(fp_line
			(start -0.67945 0.3048)
			(end -0.67945 -0.305054)
			(stroke
				(width 0.1)
				(type default)
			)
			(layer "F.Fab")
		)
		(fp_line
			(start -0.12065 0.3048)
			(end -0.67945 0.3048)
			(stroke
				(width 0.1)
				(type default)
			)
			(layer "F.Fab")
		)
		(fp_line
			(start 0.120396 0.3048)
			(end 0.120396 0.2794)
			(stroke
				(width 0.1)
				(type default)
			)
			(layer "F.Fab")
		)
		(fp_line
			(start 0.67945 0.3048)
			(end 0.120396 0.3048)
			(stroke
				(width 0.1)
				(type default)
			)
			(layer "F.Fab")
		)
		(fp_line
			(start -0.12065 0.2794)
			(end -0.12065 0.3048)
			(stroke
				(width 0.1)
				(type default)
			)
			(layer "F.Fab")
		)
		(fp_line
			(start 0.120396 0.2794)
			(end -0.12065 0.2794)
			(stroke
				(width 0.1)
				(type default)
			)
			(layer "F.Fab")
		)
		(fp_line
			(start -0.12065 -0.2794)
			(end 0.12065 -0.2794)
			(stroke
				(width 0.1)
				(type default)
			)
			(layer "F.Fab")
		)
		(fp_line
			(start 0.12065 -0.2794)
			(end 0.12065 -0.3048)
			(stroke
				(width 0.1)
				(type default)
			)
			(layer "F.Fab")
		)
		(fp_line
			(start 0.12065 -0.3048)
			(end 0.67945 -0.3048)
			(stroke
				(width 0.1)
				(type default)
			)
			(layer "F.Fab")
		)
		(fp_line
			(start 0.67945 -0.3048)
			(end 0.67945 0.3048)
			(stroke
				(width 0.1)
				(type default)
			)
			(layer "F.Fab")
		)
		(fp_line
			(start -0.67945 -0.305054)
			(end -0.12065 -0.305054)
			(stroke
				(width 0.1)
				(type default)
			)
			(layer "F.Fab")
		)
		(fp_line
			(start -0.12065 -0.305054)
			(end -0.12065 -0.2794)
			(stroke
				(width 0.1)
				(type default)
			)
			(layer "F.Fab")
		)
		(pad "1" smd circle
			(at -0.40005 0 270)
			(size 0 0)
			(layers "F.Cu" "F.Mask" "F.Paste")
			(net "PVCCIN_CPU1")
		)
		(pad "2" smd circle
			(at 0.40005 0 270)
			(size 0 0)
			(layers "F.Cu" "F.Mask" "F.Paste")
			(net "GND")
		)
	)
)
